# T6G (Grand Teton) — schematic netlist excerpt (pin names and nets, part order shuffled) for the footprints in the layout excerpt that follows; sources: Cadence DE-HDL packaged netlist, KiCad conversion of 04192023_DAF0TMB3IC0_F0TG_MB_C_brd_V02_OCP.brd

PL40  Q_INDUCTOR4P_14  150NH IND  pkg L_TLM117513Q-151QL_11X7-5XA  page 218
  \1\  = SW_PVDDCR_CPU1_P1_SW1
  \2\  = IND_CPU1_P1_CPL5
  \3\  = IND_CPU1_P1_CPL1
  \4\  = PVDDCR_CPU1_P1

U239  74LVC1G126SE7  74LVC1G126SE-7 IC  pkg SOT353_0-65_2X1-25  page 144
  OE  = PU_BUFFER_HDD_ACTIVITY
  A  = LED_HDD_ACTIVITY_N
  GND  = GND
  Y  = LED_HDD_ACTIVITY_B_N
  VCC  = P3V3_AUX

(kicad_pcb
	(version 20260206)
	(generator "pcbnew")
	(generator_version "10.0")
	(general
		(thickness 1.6)
		(legacy_teardrops no)
	)
	(paper "A4")
	(title_block
		(title "04192023_DAF0TMB3IC0_F0TG_MB_C_brd_V02_OCP.brd")
		(comment 1 "Grand Teton / footprints 2671-2672 of 8354")
	)
	(layers
		(0 "F.Cu" signal "TOP")
		(4 "In1.Cu" signal "GND")
		(6 "In2.Cu" signal "IN1")
		(8 "In3.Cu" signal "GND1")
		(10 "In4.Cu" signal "IN2")
		(12 "In5.Cu" signal "GND2")
		(14 "In6.Cu" signal "IN3")
		(16 "In7.Cu" signal "GND3")
		(18 "In8.Cu" signal "VCC")
		(20 "In9.Cu" signal "VCC1")
		(22 "In10.Cu" signal "GND4")
		(24 "In11.Cu" signal "IN4")
		(26 "In12.Cu" signal "GND5")
		(28 "In13.Cu" signal "IN5")
		(30 "In14.Cu" signal "GND6")
		(32 "In15.Cu" signal "IN6")
		(34 "In16.Cu" signal "GND7")
		(2 "B.Cu" signal "BOTTOM")
		(9 "F.Adhes" user "F.Adhesive")
		(11 "B.Adhes" user "B.Adhesive")
		(13 "F.Paste" user "Package Geometry/Pastemask Top")
		(15 "B.Paste" user "Package Geometry/Pastemask Bottom")
		(5 "F.SilkS" user "Ref Des/Silkscreen Top")
		(7 "B.SilkS" user "Ref Des/Silkscreen Bottom")
		(1 "F.Mask" user "Board Geometry/Soldermask Top")
		(3 "B.Mask" user "Board Geometry/Soldermask Bottom")
		(17 "Dwgs.User" user "User.Drawings")
		(19 "Cmts.User" user "User.Comments")
		(21 "Eco1.User" user "User.Eco1")
		(23 "Eco2.User" user "User.Eco2")
		(25 "Edge.Cuts" user "Board Geometry/Outline")
		(27 "Margin" user)
		(31 "F.CrtYd" user "Package Geometry/Place Bound Top")
		(29 "B.CrtYd" user "Package Geometry/Place Bound Bottom")
		(35 "F.Fab" user "Ref Des/Assembly Top")
		(33 "B.Fab" user "Ref Des/Assembly Bottom")
	)
	(footprint ""
		(layer "F.Cu")
		(at 154.17419 -102.688898)
		(property "Reference" "U239"
			(at -2.004314 1.730248 0)
			(unlocked yes)
			(layer "F.SilkS")
			(effects
				(font
					(size 0.7874 0.5842)
					(thickness 0.1524)
				)
				(justify left)
			)
		)
		(property "Value" ""
			(at 0 0 0)
			(layer "F.Fab")
			(effects
				(font
					(size 1.27 1.27)
				)
			)
		)
		(duplicate_pad_numbers_are_jumpers no)
		(fp_line
			(start -1.400048 1.100074)
			(end -1.400048 -1.100074)
			(stroke
				(width 0.1524)
				(type default)
			)
			(layer "F.SilkS")
		)
		(fp_line
			(start 1.400048 -1.100074)
			(end -1.400048 -1.100074)
			(stroke
				(width 0.1524)
				(type default)
			)
			(layer "F.SilkS")
		)
		(fp_line
			(start 1.400048 -1.100074)
			(end 1.400048 1.100074)
			(stroke
				(width 0.1524)
				(type default)
			)
			(layer "F.SilkS")
		)
		(fp_line
			(start 1.400048 1.100074)
			(end -1.400048 1.100074)
			(stroke
				(width 0.1524)
				(type default)
			)
			(layer "F.SilkS")
		)
		(fp_poly
			(pts
				(xy -2.606548 -0.418846) (xy -2.606548 -1.434846) (xy -1.590548 -0.926846)
			)
			(stroke
				(width 0)
				(type default)
			)
			(fill yes)
			(layer "F.SilkS")
		)
		(fp_line
			(start -0.674878 -1.100074)
			(end 0.674878 -1.100074)
			(stroke
				(width 0.1)
				(type default)
			)
			(layer "F.Fab")
		)
		(fp_line
			(start -0.674878 1.100074)
			(end -0.674878 -1.100074)
			(stroke
				(width 0.1)
				(type default)
			)
			(layer "F.Fab")
		)
		(fp_line
			(start 0.674878 -1.100074)
			(end 0.674878 1.100074)
			(stroke
				(width 0.1)
				(type default)
			)
			(layer "F.Fab")
		)
		(fp_line
			(start 0.674878 1.100074)
			(end -0.674878 1.100074)
			(stroke
				(width 0.1)
				(type default)
			)
			(layer "F.Fab")
		)
		(fp_poly
			(pts
				(xy -1.590548 -0.649986) (xy -2.606548 -1.157986) (xy -2.606548 -0.141986)
			)
			(stroke
				(width 0)
				(type default)
			)
			(fill yes)
			(layer "F.Fab")
		)
		(pad "1" smd rect
			(at -0.94996 -0.649986 270)
			(size 0.4318 0.6096)
			(layers "F.Cu" "F.Mask" "F.Paste")
			(net "PU_BUFFER_HDD_ACTIVITY")
		)
		(pad "2" smd rect
			(at -0.94996 0 270)
			(size 0.4318 0.6096)
			(layers "F.Cu" "F.Mask" "F.Paste")
			(net "LED_HDD_ACTIVITY_N")
		)
		(pad "3" smd rect
			(at -0.94996 0.649986 270)
			(size 0.4318 0.6096)
			(layers "F.Cu" "F.Mask" "F.Paste")
			(net "GND")
		)
		(pad "4" smd rect
			(at 0.94996 0.649986 270)
			(size 0.4318 0.6096)
			(layers "F.Cu" "F.Mask" "F.Paste")
			(net "LED_HDD_ACTIVITY_B_N")
		)
		(pad "5" smd rect
			(at 0.94996 -0.649986 270)
			(size 0.4318 0.6096)
			(layers "F.Cu" "F.Mask" "F.Paste")
			(net "P3V3_AUX")
		)
	)
	(footprint ""
		(layer "F.Cu")
		(at 87.24011 -325.661274)
		(property "Reference" "PL40"
			(at -3.16611 -16.704056 0)
			(unlocked yes)
			(layer "F.SilkS")
			(effects
				(font
					(size 0.7874 0.5842)
					(thickness 0.1524)
				)
				(justify left)
			)
		)
		(property "Value" ""
			(at 0 0 0)
			(layer "F.Fab")
			(effects
				(font
					(size 1.27 1.27)
				)
			)
		)
		(duplicate_pad_numbers_are_jumpers no)
		(fp_line
			(start -3.750056 -5.500116)
			(end -2.393442 -5.500116)
			(stroke
				(width 0.1524)
				(type default)
			)
			(layer "F.SilkS")
		)
		(fp_line
			(start -3.750056 5.500116)
			(end -3.750056 -5.500116)
			(stroke
				(width 0.1524)
				(type default)
			)
			(layer "F.SilkS")
		)
		(fp_line
			(start -2.393442 5.500116)
			(end -3.750056 5.500116)
			(stroke
				(width 0.1524)
				(type default)
			)
			(layer "F.SilkS")
		)
		(fp_line
			(start 2.393442 5.500116)
			(end 3.750056 5.500116)
			(stroke
				(width 0.1524)
				(type default)
			)
			(layer "F.SilkS")
		)
		(fp_line
			(start 3.750056 -5.500116)
			(end 2.393442 -5.500116)
			(stroke
				(width 0.1524)
				(type default)
			)
			(layer "F.SilkS")
		)
		(fp_line
			(start 3.750056 5.500116)
			(end 3.750056 -5.500116)
			(stroke
				(width 0.1524)
				(type default)
			)
			(layer "F.SilkS")
		)
		(fp_poly
			(pts
				(xy -3.9116 -4.249928) (xy -4.3434 -4.034028) (xy -4.3434 -4.465828)
			)
			(stroke
				(width 0)
				(type default)
			)
			(fill yes)
			(layer "F.SilkS")
		)
		(fp_line
			(start -3.750056 -5.500116)
			(end -3.750056 5.500116)
			(stroke
				(width 0.1)
				(type default)
			)
			(layer "F.Fab")
		)
		(fp_line
			(start -3.750056 5.500116)
			(end 3.750056 5.500116)
			(stroke
				(width 0.1)
				(type default)
			)
			(layer "F.Fab")
		)
		(fp_line
			(start 3.750056 -5.500116)
			(end -3.750056 -5.500116)
			(stroke
				(width 0.1)
				(type default)
			)
			(layer "F.Fab")
		)
		(fp_line
			(start 3.750056 5.500116)
			(end 3.750056 -5.500116)
			(stroke
				(width 0.1)
				(type default)
			)
			(layer "F.Fab")
		)
		(fp_poly
			(pts
				(xy -4.9276 -4.757928) (xy -4.9276 -3.741928) (xy -3.9116 -4.249928)
			)
			(stroke
				(width 0)
				(type default)
			)
			(fill yes)
			(layer "F.Fab")
		)
		(pad "1" smd rect
			(at 0 -4.249928 270)
			(size 2.413 4.5212)
			(layers "F.Cu" "F.Mask" "F.Paste")
			(net "SW_PVDDCR_CPU1_P1_SW1")
		)
		(pad "2" smd rect
			(at 0 -1.175004 270)
			(size 1.3716 4.5212)
			(layers "F.Cu" "F.Mask" "F.Paste")
			(net "IND_CPU1_P1_CPL5")
		)
		(pad "3" smd rect
			(at 0 1.175004 270)
			(size 1.3716 4.5212)
			(layers "F.Cu" "F.Mask" "F.Paste")
			(net "IND_CPU1_P1_CPL1")
		)
		(pad "4" smd rect
			(at 0 4.249928 270)
			(size 2.413 4.5212)
			(layers "F.Cu" "F.Mask" "F.Paste")
			(net "PVDDCR_CPU1_P1")
		)
	)
)
